FILE_TYPE = CONNECTIVITY;
{Allegro Design Entry HDL 16.6-p007 (v16-6-112F) 10/10/2012}
"PAGE_NUMBER" = 74;
0"NC";
1"GND\g";
2"GND\g";
3"GND\g";
4"GND\g";
5"GND\g";
6"GND\g";
7"GND\g";
8"GND\g";
%"GND"
"1","(-7625,475)","0","mstr_symbols","I1";
;
VOLTAGE"0.0V"
SIZE"1B"
CDS_LIB"mstr_symbols"
BODY_TYPE"PLUMBING"
HDL_POWER"GND";
"A\NAC"1;
%"GND"
"1","(-2425,500)","0","mstr_symbols","I11";
;
VOLTAGE"0.0V"
CDS_LIB"mstr_symbols"
SIZE"1B"
BODY_TYPE"PLUMBING"
HDL_POWER"GND";
"A\NAC"2;
%"GND"
"1","(-2025,475)","0","mstr_symbols","I12";
;
VOLTAGE"0.0V"
SIZE"1B"
CDS_LIB"mstr_symbols"
BODY_TYPE"PLUMBING"
HDL_POWER"GND";
"A\NAC"3;
%"GND"
"1","(-500,475)","0","mstr_symbols","I14";
;
VOLTAGE"0.0V"
SIZE"1B"
CDS_LIB"mstr_symbols"
BODY_TYPE"PLUMBING"
HDL_POWER"GND";
"A\NAC"4;
%"SKX_EXT_B"
"23","(-6875,2600)","0","chpset_lib","I20";
;
CDS_SEC"23"
LOCATION"U2D1"
PART_NUMBER"TBD"
MATERIAL"IC"
PACK_TYPE"BGA1"
SEC_TYPE"BGA1"
CDS_LIB"chpset_lib"
SEC"23"
CDS_LOCATION"U2D1";
"VSS<1094>"
$PN"J74"5;
"VSS<1095>"
$PN"J72"5;
"VSS<1096>"
$PN"J40"5;
"VSS<1097>"
$PN"J38"5;
"VSS<1098>"
$PN"J34"5;
"VSS<1099>"
$PN"J32"5;
"VSS<1100>"
$PN"J28"5;
"VSS<1101>"
$PN"J26"5;
"VSS<1102>"
$PN"J22"5;
"VSS<1103>"
$PN"J14"5;
"VSS<1104>"
$PN"J12"5;
"VSS<1105>"
$PN"J4"5;
"VSS<1106>"
$PN"DN44"5;
"VSS<1107>"
$PN"H75"5;
"VSS<1108>"
$PN"H71"5;
"VSS<1109>"
$PN"H65"5;
"VSS<1110>"
$PN"H41"5;
"VSS<1111>"
$PN"H39"5;
"VSS<1112>"
$PN"H37"5;
"VSS<1113>"
$PN"H35"5;
"VSS<1114>"
$PN"H33"5;
"VSS<1115>"
$PN"H31"5;
"VSS<1116>"
$PN"H29"5;
"VSS<1117>"
$PN"H27"5;
"VSS<1118>"
$PN"H25"5;
"VSS<1119>"
$PN"H11"5;
"VSS<1120>"
$PN"H3"5;
"VSS<1121>"
$PN"G82"5;
"VSS<1122>"
$PN"G80"5;
"VSS<1123>"
$PN"G78"5;
"VSS<1124>"
$PN"G76"5;
"VSS<1125>"
$PN"G70"5;
"VSS<1126>"
$PN"G66"5;
"VSS<1127>"
$PN"G42"5;
"VSS<1128>"
$PN"G38"5;
"VSS<1129>"
$PN"G36"5;
"VSS<1130>"
$PN"G32"5;
"VSS<1131>"
$PN"G30"5;
"VSS<1132>"
$PN"G26"5;
"VSS<1133>"
$PN"G24"5;
"VSS<1134>"
$PN"G22"5;
"VSS<1135>"
$PN"G8"5;
"VSS<1136>"
$PN"G4"5;
"VSS<1137>"
$PN"F69"5;
"VSS<1138>"
$PN"F67"5;
"VSS<1139>"
$PN"F43"5;
"VSS<1140>"
$PN"F37"5;
"VSS<1141>"
$PN"F31"5;
"VSS<1142>"
$PN"F25"5;
"VSS<1143>"
$PN"F19"5;
"VSS<1144>"
$PN"F17"5;
"VSS<1145>"
$PN"F5"5;
"VSS<1146>"
$PN"E76"5;
"VSS<1147>"
$PN"E74"5;
"VSS<1148>"
$PN"E72"5;
"VSS<1149>"
$PN"E22"5;
"VSS<1150>"
$PN"E20"5;
"VSS<1151>"
$PN"E18"5;
"VSS<1152>"
$PN"E16"5;
"VSS<1153>"
$PN"E8"5;
"VSS<1154>"
$PN"E6"5;
"VSS<1155>"
$PN"D77"5;
"VSS<1156>"
$PN"D43"5;
"VSS<1157>"
$PN"D41"5;
"VSS<1158>"
$PN"D39"5;
"VSS<1159>"
$PN"D37"5;
"VSS<1160>"
$PN"D35"5;
"VSS<1161>"
$PN"D33"5;
"VSS<1162>"
$PN"D31"5;
"VSS<1163>"
$PN"D29"5;
"VSS<1164>"
$PN"D27"5;
"VSS<1165>"
$PN"D25"5;
"VSS<1166>"
$PN"D13"5;
"VSS<1167>"
$PN"D11"5;
"VSS<1168>"
$PN"CM27"5;
"VSS<1169>"
$PN"C78"5;
"VSS<1170>"
$PN"C76"5;
"VSS<1171>"
$PN"C16"5;
"VSS<1172>"
$PN"C14"5;
"VSS<1173>"
$PN"C12"5;
"VSS<1174>"
$PN"C10"1;
"VSS<1175>"
$PN"C8"1;
"VSS<1176>"
$PN"B75"1;
"VSS<1177>"
$PN"B71"1;
"VSS<1178>"
$PN"B37"1;
"VSS<1179>"
$PN"B31"1;
"VSS<1180>"
$PN"B25"1;
"VSS<1181>"
$PN"A38"1;
"VSS<1182>"
$PN"A36"1;
"VSS<1183>"
$PN"A32"1;
"VSS<1184>"
$PN"A30"1;
"VSS<1185>"
$PN"A26"1;
"VSS<1186>"
$PN"AC58"1;
"VSS<1187>"
$PN"AC60"1;
"VSS<1188>"
$PN"AC62"1;
"VSS<1189>"
$PN"AJ4"1;
"VSS<1190>"
$PN"AR6"1;
"VSS<1191>"
$PN"CG6"1;
"VSS<1192>"
$PN"CW6"1;
"VSS<1193>"
$PN"DE48"1;
"VSS<1194>"
$PN"DE50"1;
"VSS<1195>"
$PN"DE52"1;
"VSS<1196>"
$PN"DE54"1;
"VSS<1197>"
$PN"DE56"1;
"VSS<1198>"
$PN"DE58"1;
"VSS<1199>"
$PN"DE60"1;
"VSS<1200>"
$PN"DE62"1;
"VSS<1201>"
$PN"DL8"1;
"VSS<1202>"
$PN"DN18"1;
"VSS<1203>"
$PN"DP45"1;
"VSS<1204>"
$PN"DP47"1;
"VSS<1205>"
$PN"DP49"1;
"VSS<1206>"
$PN"DP51"1;
"VSS<1207>"
$PN"DP53"1;
"VSS<1208>"
$PN"DP55"1;
"VSS<1209>"
$PN"DP57"1;
"VSS<1210>"
$PN"DP59"1;
"VSS<1211>"
$PN"DP61"1;
"VSS<1212>"
$PN"DP63"1;
"VSS<1213>"
$PN"DP9"1;
"VSS<1214>"
$PN"DV19"1;
"VSS<1215>"
$PN"DY45"1;
"VSS<1216>"
$PN"DY47"1;
"VSS<1217>"
$PN"DY49"1;
"VSS<1218>"
$PN"DY51"1;
"VSS<1219>"
$PN"DY53"1;
"VSS<1220>"
$PN"DY55"1;
"VSS<1221>"
$PN"DY57"1;
"VSS<1222>"
$PN"DY59"1;
"VSS<1223>"
$PN"DY61"1;
"VSS<1224>"
$PN"DY63"1;
"VSS<1225>"
$PN"EA14"1;
"VSS<1226>"
$PN"L8"1;
"VSS<1227>"
$PN"V11"1;
"VSS<1228>"
$PN"E66"1;
"VSS<1229>"
$PN"ED69"1;
"VSS<1230>"
$PN"EE80"1;
"VSS<1231>"
$PN"EE8"1;
"VSS<1232>"
$PN"EE40"1;
"VSS<1233>"
$PN"ED81"1;
"VSS<1234>"
$PN"ED7"1;
"VSS<1235>"
$PN"ED41"1;
"VSS<1236>"
$PN"EC82"1;
"VSS<1237>"
$PN"EC6"1;
"VSS<1238>"
$PN"EC42"1;
"VSS<1239>"
$PN"DW2"1;
"VSS<1240>"
$PN"EB83"1;
"VSS<1241>"
$PN"EA84"1;
"VSS<1242>"
$PN"DY85"1;
"VSS<1243>"
$PN"J86"1;
"VSS<1244>"
$PN"E82"1;
"VSS<1245>"
$PN"D81"1;
"VSS<1246>"
$PN"D3"1;
"VSS<1247>"
$PN"C80"1;
"VSS<1248>"
$PN"C4"1;
"VSS<1249>"
$PN"B79"1;
"VSS<1250>"
$PN"B5"1;
"VSS<1251>"
$PN"B43"1;
"VSS<1252>"
$PN"A42"1;
"VSS<1253>"
$PN"B9"1;
%"SKX_EXT_B"
"24","(-5025,2625)","0","chpset_lib","I21";
;
CDS_SEC"24"
LOCATION"U2D1"
PART_NUMBER"TBD"
MATERIAL"IC"
PACK_TYPE"BGA1"
SEC_TYPE"BGA1"
CDS_LIB"chpset_lib"
SEC"24"
CDS_LOCATION"U2D1";
"VSS<934>"
$PN"AA16"7;
"VSS<935>"
$PN"AA4"7;
"VSS<936>"
$PN"Y85"7;
"VSS<937>"
$PN"Y83"7;
"VSS<938>"
$PN"Y81"7;
"VSS<939>"
$PN"Y79"7;
"VSS<940>"
$PN"Y73"7;
"VSS<941>"
$PN"Y71"7;
"VSS<942>"
$PN"Y9"7;
"VSS<943>"
$PN"Y7"7;
"VSS<944>"
$PN"Y67"7;
"VSS<945>"
$PN"Y5"7;
"VSS<946>"
$PN"Y17"7;
"VSS<947>"
$PN"Y15"7;
"VSS<948>"
$PN"W82"7;
"VSS<949>"
$PN"W78"7;
"VSS<950>"
$PN"W74"7;
"VSS<951>"
$PN"W68"7;
"VSS<952>"
$PN"W42"7;
"VSS<953>"
$PN"W40"7;
"VSS<954>"
$PN"W38"7;
"VSS<955>"
$PN"W36"7;
"VSS<956>"
$PN"W34"7;
"VSS<957>"
$PN"W32"7;
"VSS<958>"
$PN"W30"7;
"VSS<959>"
$PN"W28"7;
"VSS<960>"
$PN"W26"7;
"VSS<961>"
$PN"W24"7;
"VSS<962>"
$PN"W22"7;
"VSS<963>"
$PN"W12"7;
"VSS<964>"
$PN"AC56"7;
"VSS<965>"
$PN"W8"7;
"VSS<966>"
$PN"V83"7;
"VSS<967>"
$PN"V77"7;
"VSS<968>"
$PN"V75"7;
"VSS<969>"
$PN"V73"7;
"VSS<970>"
$PN"V43"7;
"VSS<971>"
$PN"V23"7;
"VSS<972>"
$PN"V21"7;
"VSS<973>"
$PN"V15"7;
"VSS<974>"
$PN"V13"7;
"VSS<975>"
$PN"V9"7;
"VSS<976>"
$PN"V5"7;
"VSS<977>"
$PN"V1"7;
"VSS<978>"
$PN"U86"7;
"VSS<979>"
$PN"U80"7;
"VSS<980>"
$PN"U78"7;
"VSS<981>"
$PN"U76"7;
"VSS<982>"
$PN"U74"7;
"VSS<983>"
$PN"U70"7;
"VSS<984>"
$PN"U68"7;
"VSS<985>"
$PN"U42"7;
"VSS<986>"
$PN"U36"7;
"VSS<987>"
$PN"U30"7;
"VSS<988>"
$PN"U24"7;
"VSS<989>"
$PN"U22"7;
"VSS<990>"
$PN"U20"7;
"VSS<991>"
$PN"U6"7;
"VSS<992>"
$PN"U4"7;
"VSS<993>"
$PN"U2"7;
"VSS<994>"
$PN"T85"7;
"VSS<995>"
$PN"T83"7;
"VSS<996>"
$PN"T77"7;
"VSS<997>"
$PN"T73"7;
"VSS<998>"
$PN"T65"7;
"VSS<999>"
$PN"T41"7;
"VSS<1000>"
$PN"T37"7;
"VSS<1001>"
$PN"T35"7;
"VSS<1002>"
$PN"T31"7;
"VSS<1003>"
$PN"T29"7;
"VSS<1004>"
$PN"T25"7;
"VSS<1005>"
$PN"T17"7;
"VSS<1006>"
$PN"T13"7;
"VSS<1007>"
$PN"R86"7;
"VSS<1008>"
$PN"R78"7;
"VSS<1009>"
$PN"R72"7;
"VSS<1010>"
$PN"R68"7;
"VSS<1011>"
$PN"R40"7;
"VSS<1012>"
$PN"R38"7;
"VSS<1013>"
$PN"R34"7;
"VSS<1014>"
$PN"R32"6;
"VSS<1015>"
$PN"R28"6;
"VSS<1016>"
$PN"R26"6;
"VSS<1017>"
$PN"R22"6;
"VSS<1018>"
$PN"R4"6;
"VSS<1019>"
$PN"R2"6;
"VSS<1020>"
$PN"R18"6;
"VSS<1021>"
$PN"R14"6;
"VSS<1022>"
$PN"P83"6;
"VSS<1023>"
$PN"P81"6;
"VSS<1024>"
$PN"P71"6;
"VSS<1025>"
$PN"P69"6;
"VSS<1026>"
$PN"P67"6;
"VSS<1027>"
$PN"P39"6;
"VSS<1028>"
$PN"P33"6;
"VSS<1029>"
$PN"P27"6;
"VSS<1030>"
$PN"P15"6;
"VSS<1031>"
$PN"P11"6;
"VSS<1032>"
$PN"N8"6;
"VSS<1033>"
$PN"N4"6;
"VSS<1034>"
$PN"N78"6;
"VSS<1035>"
$PN"N76"6;
"VSS<1036>"
$PN"N74"6;
"VSS<1037>"
$PN"N72"6;
"VSS<1038>"
$PN"N70"6;
"VSS<1039>"
$PN"N66"6;
"VSS<1040>"
$PN"N6"6;
"VSS<1041>"
$PN"N22"6;
"VSS<1042>"
$PN"N20"6;
"VSS<1043>"
$PN"DM19"6;
"VSS<1044>"
$PN"M85"6;
"VSS<1045>"
$PN"M83"6;
"VSS<1046>"
$PN"M79"6;
"VSS<1047>"
$PN"M71"6;
"VSS<1048>"
$PN"M65"6;
"VSS<1049>"
$PN"M43"6;
"VSS<1050>"
$PN"M41"6;
"VSS<1051>"
$PN"M39"6;
"VSS<1052>"
$PN"M37"6;
"VSS<1053>"
$PN"M35"6;
"VSS<1054>"
$PN"M33"6;
"VSS<1055>"
$PN"M31"6;
"VSS<1056>"
$PN"M29"6;
"VSS<1057>"
$PN"M27"6;
"VSS<1058>"
$PN"M25"6;
"VSS<1059>"
$PN"M23"6;
"VSS<1060>"
$PN"M19"6;
"VSS<1061>"
$PN"M17"6;
"VSS<1062>"
$PN"M15"6;
"VSS<1063>"
$PN"CT7"6;
"VSS<1064>"
$PN"BT9"6;
"VSS<1065>"
$PN"L82"6;
"VSS<1066>"
$PN"L80"6;
"VSS<1067>"
$PN"L78"6;
"VSS<1068>"
$PN"L72"6;
"VSS<1069>"
$PN"L22"6;
"VSS<1070>"
$PN"L20"6;
"VSS<1071>"
$PN"L6"6;
"VSS<1072>"
$PN"L2"6;
"VSS<1073>"
$PN"L10"6;
"VSS<1074>"
$PN"K85"6;
"VSS<1075>"
$PN"K83"6;
"VSS<1076>"
$PN"K81"6;
"VSS<1077>"
$PN"K77"6;
"VSS<1078>"
$PN"K73"6;
"VSS<1079>"
$PN"K71"6;
"VSS<1080>"
$PN"K69"6;
"VSS<1081>"
$PN"K67"6;
"VSS<1082>"
$PN"K65"6;
"VSS<1083>"
$PN"K39"6;
"VSS<1084>"
$PN"K33"6;
"VSS<1085>"
$PN"K27"6;
"VSS<1086>"
$PN"DB7"6;
"VSS<1087>"
$PN"K17"6;
"VSS<1088>"
$PN"K13"6;
"VSS<1089>"
$PN"K11"6;
"VSS<1090>"
$PN"K1"6;
"VSS<1091>"
$PN"J84"6;
"VSS<1092>"
$PN"J82"6;
"VSS<1093>"
$PN"J76"6;
%"SKX_EXT_B"
"25","(-3200,2625)","0","chpset_lib","I22";
;
CDS_SEC"25"
LOCATION"U2D1"
PART_NUMBER"TBD"
MATERIAL"IC"
PACK_TYPE"BGA1"
SEC_TYPE"BGA1"
CDS_LIB"chpset_lib"
SEC"25"
CDS_LOCATION"U2D1";
"VSS<774>"
$PN"AL68"2;
"VSS<775>"
$PN"AL64"2;
"VSS<776>"
$PN"AL56"2;
"VSS<777>"
$PN"AL32"2;
"VSS<778>"
$PN"AL30"2;
"VSS<779>"
$PN"AL24"2;
"VSS<780>"
$PN"AL10"2;
"VSS<781>"
$PN"AL4"2;
"VSS<782>"
$PN"AK85"2;
"VSS<783>"
$PN"AK83"2;
"VSS<784>"
$PN"AK81"2;
"VSS<785>"
$PN"AK79"2;
"VSS<786>"
$PN"AK73"2;
"VSS<787>"
$PN"AK67"2;
"VSS<788>"
$PN"AK65"2;
"VSS<789>"
$PN"AK55"2;
"VSS<790>"
$PN"AK33"2;
"VSS<791>"
$PN"AK31"2;
"VSS<792>"
$PN"AK29"2;
"VSS<793>"
$PN"AK25"2;
"VSS<794>"
$PN"AK23"2;
"VSS<795>"
$PN"AK19"2;
"VSS<796>"
$PN"AK13"2;
"VSS<797>"
$PN"AK9"2;
"VSS<798>"
$PN"AJ86"2;
"VSS<799>"
$PN"AJ82"2;
"VSS<800>"
$PN"AJ78"2;
"VSS<801>"
$PN"AJ74"2;
"VSS<802>"
$PN"AJ68"2;
"VSS<803>"
$PN"AJ66"2;
"VSS<804>"
$PN"AJ54"2;
"VSS<805>"
$PN"AJ52"2;
"VSS<806>"
$PN"AJ50"2;
"VSS<807>"
$PN"AJ48"2;
"VSS<808>"
$PN"AJ46"2;
"VSS<809>"
$PN"AJ34"2;
"VSS<810>"
$PN"AJ32"2;
"VSS<811>"
$PN"AJ28"2;
"VSS<812>"
$PN"AJ26"2;
"VSS<813>"
$PN"AJ22"2;
"VSS<814>"
$PN"AJ8"2;
"VSS<815>"
$PN"AH83"2;
"VSS<816>"
$PN"AH77"2;
"VSS<817>"
$PN"AH75"2;
"VSS<818>"
$PN"AH69"2;
"VSS<819>"
$PN"AH65"2;
"VSS<820>"
$PN"AH61"2;
"VSS<821>"
$PN"AH59"2;
"VSS<822>"
$PN"AH53"2;
"VSS<823>"
$PN"AH51"2;
"VSS<824>"
$PN"AH49"2;
"VSS<825>"
$PN"AH47"2;
"VSS<826>"
$PN"AH45"2;
"VSS<827>"
$PN"AH35"2;
"VSS<828>"
$PN"AH33"2;
"VSS<829>"
$PN"AH27"2;
"VSS<830>"
$PN"AH21"2;
"VSS<831>"
$PN"AH5"2;
"VSS<832>"
$PN"AH1"2;
"VSS<833>"
$PN"AG80"2;
"VSS<834>"
$PN"AG78"2;
"VSS<835>"
$PN"AG76"2;
"VSS<836>"
$PN"AG74"2;
"VSS<837>"
$PN"AG70"2;
"VSS<838>"
$PN"AG64"2;
"VSS<839>"
$PN"AG36"2;
"VSS<840>"
$PN"AG18"2;
"VSS<841>"
$PN"AG14"2;
"VSS<842>"
$PN"AG12"2;
"VSS<843>"
$PN"AF85"2;
"VSS<844>"
$PN"AF83"2;
"VSS<845>"
$PN"AF77"2;
"VSS<846>"
$PN"AF73"2;
"VSS<847>"
$PN"AF41"2;
"VSS<848>"
$PN"AF39"2;
"VSS<849>"
$PN"AF37"2;
"VSS<850>"
$PN"AF33"2;
"VSS<851>"
$PN"AF31"2;
"VSS<852>"
$PN"AF29"2;
"VSS<853>"
$PN"AF27"2;
"VSS<854>"
$PN"AF25"8;
"VSS<855>"
$PN"AF23"8;
"VSS<856>"
$PN"AF21"8;
"VSS<857>"
$PN"AF9"8;
"VSS<858>"
$PN"AC52"8;
"VSS<859>"
$PN"AF1"8;
"VSS<860>"
$PN"AE78"8;
"VSS<861>"
$PN"AE70"8;
"VSS<862>"
$PN"AE68"8;
"VSS<863>"
$PN"AE66"8;
"VSS<864>"
$PN"AE64"8;
"VSS<865>"
$PN"AE42"8;
"VSS<866>"
$PN"AE40"8;
"VSS<867>"
$PN"AE38"8;
"VSS<868>"
$PN"AE16"8;
"VSS<869>"
$PN"AC54"8;
"VSS<870>"
$PN"AE8"8;
"VSS<871>"
$PN"AE4"8;
"VSS<872>"
$PN"AD85"8;
"VSS<873>"
$PN"AD83"8;
"VSS<874>"
$PN"AD81"8;
"VSS<875>"
$PN"AD75"8;
"VSS<876>"
$PN"AD73"8;
"VSS<877>"
$PN"AD71"8;
"VSS<878>"
$PN"AD43"8;
"VSS<879>"
$PN"AD39"8;
"VSS<880>"
$PN"AD33"8;
"VSS<881>"
$PN"AD27"8;
"VSS<882>"
$PN"AD21"8;
"VSS<883>"
$PN"AD19"8;
"VSS<884>"
$PN"AD15"8;
"VSS<885>"
$PN"AD13"8;
"VSS<886>"
$PN"AD11"8;
"VSS<887>"
$PN"AD9"8;
"VSS<888>"
$PN"AD7"8;
"VSS<889>"
$PN"AD3"8;
"VSS<890>"
$PN"AC86"8;
"VSS<891>"
$PN"AC84"8;
"VSS<892>"
$PN"AC78"8;
"VSS<893>"
$PN"AC72"8;
"VSS<894>"
$PN"AC70"8;
"VSS<895>"
$PN"AC64"8;
"VSS<896>"
$PN"AC40"8;
"VSS<897>"
$PN"AC38"8;
"VSS<898>"
$PN"AC34"8;
"VSS<899>"
$PN"AC32"8;
"VSS<900>"
$PN"AC28"8;
"VSS<901>"
$PN"AC26"8;
"VSS<902>"
$PN"AC22"8;
"VSS<903>"
$PN"AC18"8;
"VSS<904>"
$PN"AB85"8;
"VSS<905>"
$PN"AB83"8;
"VSS<906>"
$PN"AB79"8;
"VSS<907>"
$PN"AB73"8;
"VSS<908>"
$PN"AB69"8;
"VSS<909>"
$PN"AB65"8;
"VSS<910>"
$PN"AB41"8;
"VSS<911>"
$PN"AB37"8;
"VSS<912>"
$PN"AB35"8;
"VSS<913>"
$PN"AB31"8;
"VSS<914>"
$PN"AB29"8;
"VSS<915>"
$PN"AB25"8;
"VSS<916>"
$PN"AB23"8;
"VSS<917>"
$PN"AB21"8;
"VSS<918>"
$PN"AB11"8;
"VSS<919>"
$PN"AB5"8;
"VSS<920>"
$PN"AB1"8;
"VSS<921>"
$PN"AA82"8;
"VSS<922>"
$PN"AA80"8;
"VSS<923>"
$PN"AA78"8;
"VSS<924>"
$PN"AA76"8;
"VSS<925>"
$PN"AA68"8;
"VSS<926>"
$PN"AA66"8;
"VSS<927>"
$PN"AA64"8;
"VSS<928>"
$PN"AA42"8;
"VSS<929>"
$PN"AA36"8;
"VSS<930>"
$PN"AA30"8;
"VSS<931>"
$PN"AA24"8;
"VSS<932>"
$PN"AA22"8;
"VSS<933>"
$PN"AA18"8;
%"SKX_EXT_B"
"26","(-1275,2600)","0","chpset_lib","I23";
;
CDS_SEC"26"
LOCATION"U2D1"
PART_NUMBER"TBD"
MATERIAL"IC"
PACK_TYPE"BGA1"
SEC_TYPE"BGA1"
CDS_LIB"chpset_lib"
SEC"26"
CDS_LOCATION"U2D1";
"VSS<614>"
$PN"BG72"4;
"VSS<615>"
$PN"BG24"4;
"VSS<616>"
$PN"BG22"4;
"VSS<617>"
$PN"BG10"4;
"VSS<618>"
$PN"BG8"4;
"VSS<619>"
$PN"BG6"4;
"VSS<620>"
$PN"BF71"4;
"VSS<621>"
$PN"BF69"4;
"VSS<622>"
$PN"BF67"4;
"VSS<623>"
$PN"BF65"4;
"VSS<624>"
$PN"BF63"4;
"VSS<625>"
$PN"BF25"4;
"VSS<626>"
$PN"BF19"4;
"VSS<627>"
$PN"BF17"4;
"VSS<628>"
$PN"BF15"4;
"VSS<629>"
$PN"BF9"4;
"VSS<630>"
$PN"BE70"4;
"VSS<631>"
$PN"BE68"4;
"VSS<632>"
$PN"BE66"4;
"VSS<633>"
$PN"BE64"4;
"VSS<634>"
$PN"BE26"4;
"VSS<635>"
$PN"BE10"4;
"VSS<636>"
$PN"BE8"4;
"VSS<637>"
$PN"BE6"4;
"VSS<638>"
$PN"BE4"4;
"VSS<639>"
$PN"BD71"4;
"VSS<640>"
$PN"BD63"4;
"VSS<641>"
$PN"BD27"4;
"VSS<642>"
$PN"BD21"4;
"VSS<643>"
$PN"BD15"4;
"VSS<644>"
$PN"BD11"4;
"VSS<645>"
$PN"BD5"4;
"VSS<646>"
$PN"BC82"4;
"VSS<647>"
$PN"BC80"4;
"VSS<648>"
$PN"BC78"4;
"VSS<649>"
$PN"BC76"4;
"VSS<650>"
$PN"BC74"4;
"VSS<651>"
$PN"BC72"4;
"VSS<652>"
$PN"BC70"4;
"VSS<653>"
$PN"BC16"4;
"VSS<654>"
$PN"BC12"4;
"VSS<655>"
$PN"BC8"4;
"VSS<656>"
$PN"BC4"4;
"VSS<657>"
$PN"BB83"4;
"VSS<658>"
$PN"BB81"4;
"VSS<659>"
$PN"BB79"4;
"VSS<660>"
$PN"BB77"4;
"VSS<661>"
$PN"BB75"4;
"VSS<662>"
$PN"BB73"4;
"VSS<663>"
$PN"BB69"4;
"VSS<664>"
$PN"BB63"4;
"VSS<665>"
$PN"BB23"4;
"VSS<666>"
$PN"BB19"4;
"VSS<667>"
$PN"BA84"4;
"VSS<668>"
$PN"BA80"4;
"VSS<669>"
$PN"BA74"4;
"VSS<670>"
$PN"BA68"4;
"VSS<671>"
$PN"BA62"4;
"VSS<672>"
$PN"BA12"4;
"VSS<673>"
$PN"BA6"4;
"VSS<674>"
$PN"BA2"4;
"VSS<675>"
$PN"AY81"4;
"VSS<676>"
$PN"AY79"4;
"VSS<677>"
$PN"AY63"4;
"VSS<678>"
$PN"AY25"4;
"VSS<679>"
$PN"AY23"4;
"VSS<680>"
$PN"AY21"4;
"VSS<681>"
$PN"AY17"4;
"VSS<682>"
$PN"AY15"4;
"VSS<683>"
$PN"AY5"4;
"VSS<684>"
$PN"AW84"4;
"VSS<685>"
$PN"AW82"4;
"VSS<686>"
$PN"AW78"4;
"VSS<687>"
$PN"AW74"4;
"VSS<688>"
$PN"AW72"4;
"VSS<689>"
$PN"AW70"4;
"VSS<690>"
$PN"AW68"4;
"VSS<691>"
$PN"AW66"4;
"VSS<692>"
$PN"AW62"4;
"VSS<693>"
$PN"AW10"4;
"VSS<694>"
$PN"AW2"3;
"VSS<695>"
$PN"AV83"3;
"VSS<696>"
$PN"AV75"3;
"VSS<697>"
$PN"AV67"3;
"VSS<698>"
$PN"AV65"3;
"VSS<699>"
$PN"AV63"3;
"VSS<700>"
$PN"AV25"3;
"VSS<701>"
$PN"AV23"3;
"VSS<702>"
$PN"AV19"3;
"VSS<703>"
$PN"AV13"3;
"VSS<704>"
$PN"AV11"3;
"VSS<705>"
$PN"AV7"3;
"VSS<706>"
$PN"AV3"3;
"VSS<707>"
$PN"AV1"3;
"VSS<708>"
$PN"AU86"3;
"VSS<709>"
$PN"AU84"3;
"VSS<710>"
$PN"AU80"3;
"VSS<711>"
$PN"AU78"3;
"VSS<712>"
$PN"AU76"3;
"VSS<713>"
$PN"AU74"3;
"VSS<714>"
$PN"AU68"3;
"VSS<715>"
$PN"AU64"3;
"VSS<716>"
$PN"AU62"3;
"VSS<717>"
$PN"AU28"3;
"VSS<718>"
$PN"AU26"3;
"VSS<719>"
$PN"AU6"3;
"VSS<720>"
$PN"AU2"3;
"VSS<721>"
$PN"AT85"3;
"VSS<722>"
$PN"AT83"3;
"VSS<723>"
$PN"AT77"3;
"VSS<724>"
$PN"AT73"3;
"VSS<725>"
$PN"AT69"3;
"VSS<726>"
$PN"AT63"3;
"VSS<727>"
$PN"AT61"3;
"VSS<728>"
$PN"AT27"3;
"VSS<729>"
$PN"AT21"3;
"VSS<730>"
$PN"AT17"3;
"VSS<731>"
$PN"AT15"3;
"VSS<732>"
$PN"P63"3;
"VSS<733>"
$PN"AC48"3;
"VSS<734>"
$PN"AR78"3;
"VSS<735>"
$PN"AR72"3;
"VSS<736>"
$PN"AR60"3;
"VSS<737>"
$PN"AR30"3;
"VSS<738>"
$PN"AR24"3;
"VSS<739>"
$PN"AR10"3;
"VSS<740>"
$PN"AP85"3;
"VSS<741>"
$PN"AP83"3;
"VSS<742>"
$PN"AP81"3;
"VSS<743>"
$PN"AP75"3;
"VSS<744>"
$PN"AP73"3;
"VSS<745>"
$PN"AP69"3;
"VSS<746>"
$PN"AP67"3;
"VSS<747>"
$PN"AP65"3;
"VSS<748>"
$PN"AP63"3;
"VSS<749>"
$PN"AP59"3;
"VSS<750>"
$PN"AP31"3;
"VSS<751>"
$PN"AP19"3;
"VSS<752>"
$PN"AP13"3;
"VSS<753>"
$PN"AP9"3;
"VSS<754>"
$PN"AP5"3;
"VSS<755>"
$PN"AN78"3;
"VSS<756>"
$PN"AN58"3;
"VSS<757>"
$PN"AN28"3;
"VSS<758>"
$PN"AN6"3;
"VSS<759>"
$PN"AN2"3;
"VSS<760>"
$PN"AM83"3;
"VSS<761>"
$PN"AM79"3;
"VSS<762>"
$PN"AM73"3;
"VSS<763>"
$PN"AM69"3;
"VSS<764>"
$PN"AM63"3;
"VSS<765>"
$PN"AM57"3;
"VSS<766>"
$PN"AM31"3;
"VSS<767>"
$PN"AC50"3;
"VSS<768>"
$PN"AM1"3;
"VSS<769>"
$PN"AL86"3;
"VSS<770>"
$PN"AL82"3;
"VSS<771>"
$PN"AL80"3;
"VSS<772>"
$PN"AL78"3;
"VSS<773>"
$PN"AL76"3;
%"GND"
"1","(-6100,475)","0","mstr_symbols","I3";
;
VOLTAGE"0.0V"
SIZE"1B"
CDS_LIB"mstr_symbols"
BODY_TYPE"PLUMBING"
HDL_POWER"GND";
"A\NAC"5;
%"GND"
"1","(-5775,500)","0","mstr_symbols","I4";
;
VOLTAGE"0.0V"
SIZE"1B"
CDS_LIB"mstr_symbols"
BODY_TYPE"PLUMBING"
HDL_POWER"GND";
"A\NAC"6;
%"GND"
"1","(-4250,500)","0","mstr_symbols","I6";
;
VOLTAGE"0.0V"
SIZE"1B"
CDS_LIB"mstr_symbols"
BODY_TYPE"PLUMBING"
HDL_POWER"GND";
"A\NAC"7;
%"GND"
"1","(-3950,500)","0","mstr_symbols","I9";
;
VOLTAGE"0.0V"
CDS_LIB"mstr_symbols"
SIZE"1B"
BODY_TYPE"PLUMBING"
HDL_POWER"GND";
"A\NAC"8;
END.
